(kicad_pcb
	(version 20260206)
	(generator "pcbnew")
	(generator_version "10.0")
	(general
		(thickness 1.6)
		(legacy_teardrops no)
	)
	(paper "A4")
	(title_block
		(title "peb — Lightning_PEB_BRD.brd")
		(comment 1 "Lightning (Wiwynn / Facebook NVMe JBOF) / footprints 1489-1495 of 2563")
	)
	(layers
		(0 "F.Cu" signal "TOP")
		(4 "In1.Cu" signal "L2GND")
		(6 "In2.Cu" signal "L3")
		(8 "In3.Cu" signal "L4VCC")
		(10 "In4.Cu" signal "L5VCC")
		(12 "In5.Cu" signal "L6")
		(14 "In6.Cu" signal "L7GND")
		(2 "B.Cu" signal "BOTTOM")
		(9 "F.Adhes" user "F.Adhesive")
		(11 "B.Adhes" user "B.Adhesive")
		(13 "F.Paste" user "Package Geometry/Pastemask Top")
		(15 "B.Paste" user "Package Geometry/Pastemask Bottom")
		(5 "F.SilkS" user "Ref Des/Silkscreen Top")
		(7 "B.SilkS" user "Ref Des/Silkscreen Bottom")
		(1 "F.Mask" user "Board Geometry/Soldermask Top")
		(3 "B.Mask" user "Board Geometry/Soldermask Bottom")
		(17 "Dwgs.User" user "User.Drawings")
		(19 "Cmts.User" user "User.Comments")
		(21 "Eco1.User" user "User.Eco1")
		(23 "Eco2.User" user "User.Eco2")
		(25 "Edge.Cuts" user "Board Geometry/Outline")
		(27 "Margin" user)
		(31 "F.CrtYd" user "Package Geometry/Place Bound Top")
		(29 "B.CrtYd" user "Package Geometry/Place Bound Bottom")
		(35 "F.Fab" user "Ref Des/Assembly Top")
		(33 "B.Fab" user "Ref Des/Assembly Bottom")
	)
	(footprint ""
		(layer "F.Cu")
		(at 17.486122 -90.103198 -90)
		(property "Reference" "R390"
			(at 0 0 270)
			(layer "F.SilkS")
			(hide yes)
			(effects
				(font
					(size 1.27 1.27)
				)
			)
		)
		(property "Value" "4K99R2F-L-GP"
			(at 0.064008 -3.993896 270)
			(unlocked yes)
			(layer "F.Fab")
			(hide yes)
			(effects
				(font
					(size 1.016 1.016)
					(thickness 0.1524)
				)
			)
		)
		(property "Device Type" "R402H16"
			(at 0.064008 -5.517896 270)
			(unlocked yes)
			(layer "F.Fab")
			(hide yes)
			(effects
				(font
					(size 1.016 1.016)
					(thickness 0.1524)
				)
			)
		)
		(duplicate_pad_numbers_are_jumpers no)
		(fp_line
			(start -0.508 -0.9398)
			(end -0.508 0.9398)
			(stroke
				(width 0.1524)
				(type default)
			)
			(layer "F.SilkS")
		)
		(fp_line
			(start 0.508 -0.9398)
			(end -0.508 -0.9398)
			(stroke
				(width 0.1524)
				(type default)
			)
			(layer "F.SilkS")
		)
		(fp_rect
			(start -0.508 0.9398)
			(end 0.508 -0.9398)
			(stroke
				(width 0)
				(type default)
			)
			(fill no)
			(layer "F.CrtYd")
		)
		(fp_rect
			(start -0.508 0.9398)
			(end 0.508 -0.9398)
			(stroke
				(width 0)
				(type default)
			)
			(fill no)
			(layer "F.Fab")
		)
		(pad "1" smd custom
			(at 0 -0.4445 270)
			(size 0.1397 0.1397)
			(layers "F.Cu" "F.Mask" "F.Paste")
			(net "GND")
			(options
				(clearance outline)
				(anchor circle)
			)
			(primitives
				(gr_poly
					(pts
						(arc
							(start -0.1778 -0.2794)
							(mid -0.249642 -0.249642)
							(end -0.2794 -0.1778)
						)
						(arc
							(start -0.2794 0.1778)
							(mid -0.249642 0.249642)
							(end -0.1778 0.2794)
						)
						(arc
							(start 0.1778 0.2794)
							(mid 0.249642 0.249642)
							(end 0.2794 0.1778)
						)
						(arc
							(start 0.2794 -0.1778)
							(mid 0.249642 -0.249642)
							(end 0.1778 -0.2794)
						)
					)
					(width 0)
					(fill yes)
				)
			)
		)
		(pad "2" smd custom
			(at 0 0.4445 270)
			(size 0.1397 0.1397)
			(layers "F.Cu" "F.Mask" "F.Paste")
			(net "LAN_SE_RSET")
			(options
				(clearance outline)
				(anchor circle)
			)
			(primitives
				(gr_poly
					(pts
						(arc
							(start -0.1778 -0.2794)
							(mid -0.249642 -0.249642)
							(end -0.2794 -0.1778)
						)
						(arc
							(start -0.2794 0.1778)
							(mid -0.249642 0.249642)
							(end -0.1778 0.2794)
						)
						(arc
							(start 0.1778 0.2794)
							(mid 0.249642 0.249642)
							(end 0.2794 0.1778)
						)
						(arc
							(start 0.2794 -0.1778)
							(mid 0.249642 -0.249642)
							(end 0.1778 -0.2794)
						)
					)
					(width 0)
					(fill yes)
				)
			)
		)
	)
	(footprint ""
		(layer "F.Cu")
		(at 346.689172 -42.697908 90)
		(property "Reference" "R7908"
			(at 0 0 90)
			(layer "F.SilkS")
			(hide yes)
			(effects
				(font
					(size 1.27 1.27)
				)
			)
		)
		(property "Value" "0R2J-2-GP"
			(at 0.064008 -3.993896 90)
			(unlocked yes)
			(layer "F.Fab")
			(hide yes)
			(effects
				(font
					(size 1.016 1.016)
					(thickness 0.1524)
				)
			)
		)
		(property "Device Type" "R402H16"
			(at 0.064008 -5.517896 90)
			(unlocked yes)
			(layer "F.Fab")
			(hide yes)
			(effects
				(font
					(size 1.016 1.016)
					(thickness 0.1524)
				)
			)
		)
		(duplicate_pad_numbers_are_jumpers no)
		(fp_line
			(start 0.508 -0.9398)
			(end -0.508 -0.9398)
			(stroke
				(width 0.1524)
				(type default)
			)
			(layer "F.SilkS")
		)
		(fp_line
			(start -0.508 -0.9398)
			(end -0.508 0.9398)
			(stroke
				(width 0.1524)
				(type default)
			)
			(layer "F.SilkS")
		)
		(fp_rect
			(start -0.508 0.9398)
			(end 0.508 -0.9398)
			(stroke
				(width 0)
				(type default)
			)
			(fill no)
			(layer "F.CrtYd")
		)
		(fp_rect
			(start -0.508 0.9398)
			(end 0.508 -0.9398)
			(stroke
				(width 0)
				(type default)
			)
			(fill no)
			(layer "F.Fab")
		)
		(pad "1" smd custom
			(at 0 -0.4445 90)
			(size 0.1397 0.1397)
			(layers "F.Cu" "F.Mask" "F.Paste")
			(net "HB_OUT")
			(options
				(clearance outline)
				(anchor circle)
			)
			(primitives
				(gr_poly
					(pts
						(arc
							(start -0.1778 -0.2794)
							(mid -0.249642 -0.249642)
							(end -0.2794 -0.1778)
						)
						(arc
							(start -0.2794 0.1778)
							(mid -0.249642 0.249642)
							(end -0.1778 0.2794)
						)
						(arc
							(start 0.1778 0.2794)
							(mid 0.249642 0.249642)
							(end 0.2794 0.1778)
						)
						(arc
							(start 0.2794 -0.1778)
							(mid 0.249642 -0.249642)
							(end 0.1778 -0.2794)
						)
					)
					(width 0)
					(fill yes)
				)
			)
		)
		(pad "2" smd custom
			(at 0 0.4445 90)
			(size 0.1397 0.1397)
			(layers "F.Cu" "F.Mask" "F.Paste")
			(net "Q37_G")
			(options
				(clearance outline)
				(anchor circle)
			)
			(primitives
				(gr_poly
					(pts
						(arc
							(start -0.1778 -0.2794)
							(mid -0.249642 -0.249642)
							(end -0.2794 -0.1778)
						)
						(arc
							(start -0.2794 0.1778)
							(mid -0.249642 0.249642)
							(end -0.1778 0.2794)
						)
						(arc
							(start 0.1778 0.2794)
							(mid 0.249642 0.249642)
							(end 0.2794 0.1778)
						)
						(arc
							(start 0.2794 -0.1778)
							(mid 0.249642 -0.249642)
							(end 0.1778 -0.2794)
						)
					)
					(width 0)
					(fill yes)
				)
			)
		)
	)
	(footprint ""
		(layer "F.Cu")
		(at 66.802 -74.9554)
		(property "Reference" "R963"
			(at 0 0 0)
			(layer "F.SilkS")
			(hide yes)
			(effects
				(font
					(size 1.27 1.27)
				)
			)
		)
		(property "Value" "4K7R2F-GP"
			(at 0.064008 -3.993896 0)
			(unlocked yes)
			(layer "F.Fab")
			(hide yes)
			(effects
				(font
					(size 1.016 1.016)
					(thickness 0.1524)
				)
			)
		)
		(property "Device Type" "R402H16"
			(at 0.064008 -5.517896 0)
			(unlocked yes)
			(layer "F.Fab")
			(hide yes)
			(effects
				(font
					(size 1.016 1.016)
					(thickness 0.1524)
				)
			)
		)
		(duplicate_pad_numbers_are_jumpers no)
		(fp_line
			(start -0.508 -0.9398)
			(end -0.508 0.9398)
			(stroke
				(width 0.1524)
				(type default)
			)
			(layer "F.SilkS")
		)
		(fp_line
			(start 0.508 -0.9398)
			(end -0.508 -0.9398)
			(stroke
				(width 0.1524)
				(type default)
			)
			(layer "F.SilkS")
		)
		(fp_rect
			(start -0.508 0.9398)
			(end 0.508 -0.9398)
			(stroke
				(width 0)
				(type default)
			)
			(fill no)
			(layer "F.CrtYd")
		)
		(fp_rect
			(start -0.508 0.9398)
			(end 0.508 -0.9398)
			(stroke
				(width 0)
				(type default)
			)
			(fill no)
			(layer "F.Fab")
		)
		(pad "1" smd custom
			(at 0 -0.4445)
			(size 0.1397 0.1397)
			(layers "F.Cu" "F.Mask" "F.Paste")
			(net "P3V3_STBY")
			(options
				(clearance outline)
				(anchor circle)
			)
			(primitives
				(gr_poly
					(pts
						(arc
							(start -0.1778 -0.2794)
							(mid -0.249642 -0.249642)
							(end -0.2794 -0.1778)
						)
						(arc
							(start -0.2794 0.1778)
							(mid -0.249642 0.249642)
							(end -0.1778 0.2794)
						)
						(arc
							(start 0.1778 0.2794)
							(mid 0.249642 0.249642)
							(end 0.2794 0.1778)
						)
						(arc
							(start 0.2794 -0.1778)
							(mid 0.249642 -0.249642)
							(end 0.1778 -0.2794)
						)
					)
					(width 0)
					(fill yes)
				)
			)
		)
		(pad "2" smd custom
			(at 0 0.4445)
			(size 0.1397 0.1397)
			(layers "F.Cu" "F.Mask" "F.Paste")
			(net "U19_PERST_N")
			(options
				(clearance outline)
				(anchor circle)
			)
			(primitives
				(gr_poly
					(pts
						(arc
							(start -0.1778 -0.2794)
							(mid -0.249642 -0.249642)
							(end -0.2794 -0.1778)
						)
						(arc
							(start -0.2794 0.1778)
							(mid -0.249642 0.249642)
							(end -0.1778 0.2794)
						)
						(arc
							(start 0.1778 0.2794)
							(mid 0.249642 0.249642)
							(end 0.2794 0.1778)
						)
						(arc
							(start 0.2794 -0.1778)
							(mid 0.249642 -0.249642)
							(end 0.1778 -0.2794)
						)
					)
					(width 0)
					(fill yes)
				)
			)
		)
	)
	(footprint ""
		(layer "F.Cu")
		(at 301.60849 -33.540192)
		(property "Reference" "C16"
			(at 0 0 0)
			(layer "F.SilkS")
			(hide yes)
			(effects
				(font
					(size 1.27 1.27)
				)
			)
		)
		(property "Value" "SCD22U10V2KX-1GP"
			(at 1.1811 -2.7051 0)
			(unlocked yes)
			(layer "F.Fab")
			(hide yes)
			(effects
				(font
					(size 1.016 1.016)
					(thickness 0.1524)
				)
			)
		)
		(property "Device Type" "C402H22"
			(at 1.1811 -4.2291 0)
			(unlocked yes)
			(layer "F.Fab")
			(hide yes)
			(effects
				(font
					(size 1.016 1.016)
					(thickness 0.1524)
				)
			)
		)
		(duplicate_pad_numbers_are_jumpers no)
		(fp_rect
			(start -0.4318 0.9525)
			(end 0.4318 -0.9525)
			(stroke
				(width 0)
				(type default)
			)
			(fill no)
			(layer "F.CrtYd")
		)
		(fp_rect
			(start -0.4318 0.9525)
			(end 0.4318 -0.9525)
			(stroke
				(width 0)
				(type default)
			)
			(fill no)
			(layer "F.Fab")
		)
		(pad "1" smd custom
			(at 0 -0.4445)
			(size 0.1524 0.1524)
			(layers "F.Cu" "F.Mask" "F.Paste")
			(net "PCIE_TX_CAP_P6")
			(options
				(clearance outline)
				(anchor circle)
			)
			(primitives
				(gr_poly
					(pts
						(arc
							(start 0.3048 -0.2032)
							(mid 0.275042 -0.275042)
							(end 0.2032 -0.3048)
						)
						(arc
							(start -0.2032 -0.3048)
							(mid -0.275042 -0.275042)
							(end -0.3048 -0.2032)
						)
						(arc
							(start -0.3048 0.2032)
							(mid -0.275042 0.275042)
							(end -0.2032 0.3048)
						)
						(arc
							(start 0.2032 0.3048)
							(mid 0.275042 0.275042)
							(end 0.3048 0.2032)
						)
					)
					(width 0)
					(fill yes)
				)
			)
		)
		(pad "2" smd custom
			(at 0 0.4445)
			(size 0.1524 0.1524)
			(layers "F.Cu" "F.Mask" "F.Paste")
			(net "PCIE_TX_P6")
			(options
				(clearance outline)
				(anchor circle)
			)
			(primitives
				(gr_poly
					(pts
						(arc
							(start 0.3048 -0.2032)
							(mid 0.275042 -0.275042)
							(end 0.2032 -0.3048)
						)
						(arc
							(start -0.2032 -0.3048)
							(mid -0.275042 -0.275042)
							(end -0.3048 -0.2032)
						)
						(arc
							(start -0.3048 0.2032)
							(mid -0.275042 0.275042)
							(end -0.2032 0.3048)
						)
						(arc
							(start 0.2032 0.3048)
							(mid 0.275042 0.275042)
							(end 0.3048 0.2032)
						)
					)
					(width 0)
					(fill yes)
				)
			)
		)
	)
	(footprint ""
		(layer "F.Cu")
		(at 27.559 -75.2856)
		(property "Reference" "R394"
			(at 0 0 0)
			(layer "F.SilkS")
			(hide yes)
			(effects
				(font
					(size 1.27 1.27)
				)
			)
		)
		(property "Value" "10KR2F-2-GP"
			(at 0.064008 -3.993896 0)
			(unlocked yes)
			(layer "F.Fab")
			(hide yes)
			(effects
				(font
					(size 1.016 1.016)
					(thickness 0.1524)
				)
			)
		)
		(property "Device Type" "R402H16"
			(at 0.064008 -5.517896 0)
			(unlocked yes)
			(layer "F.Fab")
			(hide yes)
			(effects
				(font
					(size 1.016 1.016)
					(thickness 0.1524)
				)
			)
		)
		(duplicate_pad_numbers_are_jumpers no)
		(fp_line
			(start -0.508 -0.9398)
			(end -0.508 0.9398)
			(stroke
				(width 0.1524)
				(type default)
			)
			(layer "F.SilkS")
		)
		(fp_line
			(start 0.508 -0.9398)
			(end -0.508 -0.9398)
			(stroke
				(width 0.1524)
				(type default)
			)
			(layer "F.SilkS")
		)
		(fp_rect
			(start -0.508 0.9398)
			(end 0.508 -0.9398)
			(stroke
				(width 0)
				(type default)
			)
			(fill no)
			(layer "F.CrtYd")
		)
		(fp_rect
			(start -0.508 0.9398)
			(end 0.508 -0.9398)
			(stroke
				(width 0)
				(type default)
			)
			(fill no)
			(layer "F.Fab")
		)
		(pad "1" smd custom
			(at 0 -0.4445)
			(size 0.1397 0.1397)
			(layers "F.Cu" "F.Mask" "F.Paste")
			(net "P3V3_STBY")
			(options
				(clearance outline)
				(anchor circle)
			)
			(primitives
				(gr_poly
					(pts
						(arc
							(start -0.1778 -0.2794)
							(mid -0.249642 -0.249642)
							(end -0.2794 -0.1778)
						)
						(arc
							(start -0.2794 0.1778)
							(mid -0.249642 0.249642)
							(end -0.1778 0.2794)
						)
						(arc
							(start 0.1778 0.2794)
							(mid 0.249642 0.249642)
							(end 0.2794 0.1778)
						)
						(arc
							(start 0.2794 -0.1778)
							(mid 0.249642 -0.249642)
							(end 0.1778 -0.2794)
						)
					)
					(width 0)
					(fill yes)
				)
			)
		)
		(pad "2" smd custom
			(at 0 0.4445)
			(size 0.1397 0.1397)
			(layers "F.Cu" "F.Mask" "F.Paste")
			(net "RMII_PHY_BMC_RXD0")
			(options
				(clearance outline)
				(anchor circle)
			)
			(primitives
				(gr_poly
					(pts
						(arc
							(start -0.1778 -0.2794)
							(mid -0.249642 -0.249642)
							(end -0.2794 -0.1778)
						)
						(arc
							(start -0.2794 0.1778)
							(mid -0.249642 0.249642)
							(end -0.1778 0.2794)
						)
						(arc
							(start 0.1778 0.2794)
							(mid 0.249642 0.249642)
							(end 0.2794 0.1778)
						)
						(arc
							(start 0.2794 -0.1778)
							(mid 0.249642 -0.249642)
							(end 0.1778 -0.2794)
						)
					)
					(width 0)
					(fill yes)
				)
			)
		)
	)
	(footprint ""
		(layer "F.Cu")
		(at 69.2658 -129.794 90)
		(property "Reference" "U49"
			(at 0 0 90)
			(layer "F.SilkS")
			(hide yes)
			(effects
				(font
					(size 1.27 1.27)
				)
			)
		)
		(property "Value" "SN74AUP1T97DCKR-GP"
			(at -2.3622 -8.2042 90)
			(unlocked yes)
			(layer "F.Fab")
			(hide yes)
			(effects
				(font
					(size 1.016 1.016)
					(thickness 0.1524)
				)
			)
		)
		(property "Device Type" "SC70-6H44"
			(at -2.3622 -10.1092 90)
			(unlocked yes)
			(layer "F.Fab")
			(hide yes)
			(effects
				(font
					(size 1.016 1.016)
					(thickness 0.1524)
				)
			)
		)
		(duplicate_pad_numbers_are_jumpers no)
		(fp_line
			(start 1.4478 -1.7018)
			(end -1.4478 -1.7018)
			(stroke
				(width 0.1524)
				(type default)
			)
			(layer "F.SilkS")
		)
		(fp_line
			(start -1.4478 -1.7018)
			(end -1.4478 1.7018)
			(stroke
				(width 0.1524)
				(type default)
			)
			(layer "F.SilkS")
		)
		(fp_line
			(start 1.4478 1.7018)
			(end 1.4478 -1.7018)
			(stroke
				(width 0.1524)
				(type default)
			)
			(layer "F.SilkS")
		)
		(fp_line
			(start -1.4478 1.7018)
			(end 1.4478 1.7018)
			(stroke
				(width 0.1524)
				(type default)
			)
			(layer "F.SilkS")
		)
		(fp_line
			(start -0.5715 1.7907)
			(end -1.5494 1.7907)
			(stroke
				(width 0.3302)
				(type default)
			)
			(layer "F.SilkS")
		)
		(fp_line
			(start -1.5494 1.7907)
			(end -1.5494 0.8255)
			(stroke
				(width 0.3302)
				(type default)
			)
			(layer "F.SilkS")
		)
		(fp_poly
			(pts
				(xy -0.6604 1.7272) (xy -1.016 2.0828) (xy -0.3048 2.0828)
			)
			(stroke
				(width 0)
				(type default)
			)
			(fill yes)
			(layer "F.SilkS")
		)
		(fp_poly
			(pts
				(xy -1.524 -1.778) (xy 1.524 -1.778) (xy 1.524 1.778) (xy -1.524 1.778)
			)
			(stroke
				(width 0)
				(type default)
			)
			(fill no)
			(layer "F.CrtYd")
		)
		(fp_poly
			(pts
				(xy -1.524 -1.778) (xy 1.524 -1.778) (xy 1.524 1.778) (xy -1.524 1.778)
			)
			(stroke
				(width 0)
				(type default)
			)
			(fill no)
			(layer "F.Fab")
		)
		(pad "1" smd rect
			(at -0.65024 0.9398 90)
			(size 0.4064 1.016)
			(layers "F.Cu" "F.Mask" "F.Paste")
			(net "BMC_TXD5_R")
		)
		(pad "2" smd rect
			(at 0 0.9398 90)
			(size 0.4064 1.016)
			(layers "F.Cu" "F.Mask" "F.Paste")
			(net "GND")
		)
		(pad "3" smd rect
			(at 0.65024 0.9398 90)
			(size 0.4064 1.016)
			(layers "F.Cu" "F.Mask" "F.Paste")
			(net "GND")
		)
		(pad "4" smd rect
			(at 0.65024 -0.9398 90)
			(size 0.4064 1.016)
			(layers "F.Cu" "F.Mask" "F.Paste")
			(net "BMC_TXD5")
		)
		(pad "5" smd rect
			(at 0 -0.9398 90)
			(size 0.4064 1.016)
			(layers "F.Cu" "F.Mask" "F.Paste")
			(net "P3V3_STBY")
		)
		(pad "6" smd rect
			(at -0.65024 -0.9398 90)
			(size 0.4064 1.016)
			(layers "F.Cu" "F.Mask" "F.Paste")
			(net "GND")
		)
	)
	(footprint ""
		(layer "F.Cu")
		(at 276.606 -0.127 90)
		(property "Reference" "R2915"
			(at 0 0 90)
			(layer "F.SilkS")
			(hide yes)
			(effects
				(font
					(size 1.27 1.27)
				)
			)
		)
		(property "Value" "0R2J-2-GP"
			(at 0.064008 -3.993896 90)
			(unlocked yes)
			(layer "F.Fab")
			(hide yes)
			(effects
				(font
					(size 1.016 1.016)
					(thickness 0.1524)
				)
			)
		)
		(property "Device Type" "R402H16"
			(at 0.064008 -5.517896 90)
			(unlocked yes)
			(layer "F.Fab")
			(hide yes)
			(effects
				(font
					(size 1.016 1.016)
					(thickness 0.1524)
				)
			)
		)
		(duplicate_pad_numbers_are_jumpers no)
		(fp_line
			(start 0.508 -0.9398)
			(end -0.508 -0.9398)
			(stroke
				(width 0.1524)
				(type default)
			)
			(layer "F.SilkS")
		)
		(fp_line
			(start -0.508 -0.9398)
			(end -0.508 0.9398)
			(stroke
				(width 0.1524)
				(type default)
			)
			(layer "F.SilkS")
		)
		(fp_rect
			(start -0.508 0.9398)
			(end 0.508 -0.9398)
			(stroke
				(width 0)
				(type default)
			)
			(fill no)
			(layer "F.CrtYd")
		)
		(fp_rect
			(start -0.508 0.9398)
			(end 0.508 -0.9398)
			(stroke
				(width 0)
				(type default)
			)
			(fill no)
			(layer "F.Fab")
		)
		(pad "1" smd custom
			(at 0 -0.4445 90)
			(size 0.1397 0.1397)
			(layers "F.Cu" "F.Mask" "F.Paste")
			(net "CBL_PRSNT_N_7")
			(options
				(clearance outline)
				(anchor circle)
			)
			(primitives
				(gr_poly
					(pts
						(arc
							(start -0.1778 -0.2794)
							(mid -0.249642 -0.249642)
							(end -0.2794 -0.1778)
						)
						(arc
							(start -0.2794 0.1778)
							(mid -0.249642 0.249642)
							(end -0.1778 0.2794)
						)
						(arc
							(start 0.1778 0.2794)
							(mid 0.249642 0.249642)
							(end 0.2794 0.1778)
						)
						(arc
							(start 0.2794 -0.1778)
							(mid 0.249642 -0.249642)
							(end 0.1778 -0.2794)
						)
					)
					(width 0)
					(fill yes)
				)
			)
		)
		(pad "2" smd custom
			(at 0 0.4445 90)
			(size 0.1397 0.1397)
			(layers "F.Cu" "F.Mask" "F.Paste")
			(net "8644_SDA_R_7")
			(options
				(clearance outline)
				(anchor circle)
			)
			(primitives
				(gr_poly
					(pts
						(arc
							(start -0.1778 -0.2794)
							(mid -0.249642 -0.249642)
							(end -0.2794 -0.1778)
						)
						(arc
							(start -0.2794 0.1778)
							(mid -0.249642 0.249642)
							(end -0.1778 0.2794)
						)
						(arc
							(start 0.1778 0.2794)
							(mid 0.249642 0.249642)
							(end 0.2794 0.1778)
						)
						(arc
							(start 0.2794 -0.1778)
							(mid 0.249642 -0.249642)
							(end 0.1778 -0.2794)
						)
					)
					(width 0)
					(fill yes)
				)
			)
		)
	)
)
